FILE_TYPE = MACRO_DRAWING;
SET COLOR_WIRE YELLOW;
SET COLOR_PROP MONO;
SET COLOR_DOT WHITE;
SET COLOR_ARC YELLOW;
SET COLOR_BODY GREEN;
SET COLOR_NOTE MONO;
SET PROP_DISPLAY VALUE;
SET PAGE_NUMBER P160;
FORCEADD OFFPAGE..2
(-2175 4425);
FORCEPROP 2 LAST $XR0 163 
J 0
(-1986 4425);
DISPLAY 0.638298 (-1986 4425);
PAINT MONO (-1986 4425);
FORCEPROP 2 LAST $XR1 108 
J 0
(-1866 4425);
DISPLAY 0.638298 (-1866 4425);
PAINT MONO (-1866 4425);
FORCEPROP 2 LAST CDS_LIB mstr_standard
J 0
(-2175 4425);
PAINT ORANGE (-2175 4425);
DISPLAY INVISIBLE (-2175 4425);
FORCEPROP 1 LAST OFFPAGE TRUE
J 0
(-1850 4300);
DISPLAY 0.872340 (-1850 4300);
PAINT GREEN (-1850 4300);
DISPLAY INVISIBLE (-1850 4300);
FORCEPROP 1 LAST COMMENT_BODY TRUE
J 0
(-2220 4330);
DISPLAY 0.872340 (-2220 4330);
PAINT GREEN (-2220 4330);
DISPLAY INVISIBLE (-2220 4330);
FORCEPROP 2 LAST PATH I1
J 0
(-2000 4500);
DISPLAY 1.021277 (-2000 4500);
PAINT ORANGE (-2000 4500);
DISPLAY INVISIBLE (-2000 4500);
FORCEADD OFFPAGE..3
(-2175 3700);
FORCEPROP 2 LAST $XR0 138 
J 0
(-1961 3700);
DISPLAY 0.638298 (-1961 3700);
PAINT MONO (-1961 3700);
FORCEPROP 2 LAST $XR1 156 
J 0
(-1841 3700);
DISPLAY 0.638298 (-1841 3700);
PAINT MONO (-1841 3700);
FORCEPROP 2 LAST $XR2 182 
J 0
(-1721 3700);
DISPLAY 0.638298 (-1721 3700);
PAINT MONO (-1721 3700);
FORCEPROP 2 LAST $XR4 ?
J 0
(-1721 3700);
DISPLAY 0.638298 (-1721 3700);
PAINT MONO (-1721 3700);
FORCEPROP 2 LAST $XR3 ?
J 0
(-1721 3700);
DISPLAY 0.638298 (-1721 3700);
PAINT MONO (-1721 3700);
FORCEPROP 2 LAST CDS_LIB mstr_standard
J 0
(-2175 3700);
PAINT ORANGE (-2175 3700);
DISPLAY INVISIBLE (-2175 3700);
FORCEPROP 1 LAST OFFPAGE TRUE
J 0
(-1850 3575);
DISPLAY 0.872340 (-1850 3575);
PAINT GREEN (-1850 3575);
DISPLAY INVISIBLE (-1850 3575);
FORCEPROP 1 LAST COMMENT_BODY TRUE
J 0
(-2225 3600);
DISPLAY 0.872340 (-2225 3600);
PAINT GREEN (-2225 3600);
DISPLAY INVISIBLE (-2225 3600);
FORCEPROP 2 LAST PATH I10
J 0
(-1700 3750);
DISPLAY 1.021277 (-1700 3750);
PAINT ORANGE (-1700 3750);
DISPLAY INVISIBLE (-1700 3750);
FORCEADD OFFPAGE..4
R 2
(-4700 4425);
FORCEPROP 2 LAST $XR0 144 
J 0
(-4952 4425);
DISPLAY 0.638298 (-4952 4425);
PAINT MONO (-4952 4425);
FORCEPROP 2 LAST CDS_LIB mstr_standard
J 0
(-4700 4425);
PAINT ORANGE (-4700 4425);
DISPLAY INVISIBLE (-4700 4425);
FORCEPROP 1 LAST OFFPAGE TRUE
J 2
(-5025 4300);
DISPLAY 0.872340 (-5025 4300);
PAINT GREEN (-5025 4300);
DISPLAY INVISIBLE (-5025 4300);
FORCEPROP 1 LAST COMMENT_BODY TRUE
J 2
(-4675 4325);
DISPLAY 0.872340 (-4675 4325);
PAINT GREEN (-4675 4325);
DISPLAY INVISIBLE (-4675 4325);
FORCEPROP 2 LAST PATH I17
J 0
(-4650 4500);
DISPLAY 1.021277 (-4650 4500);
PAINT ORANGE (-4650 4500);
DISPLAY INVISIBLE (-4650 4500);
FORCEADD OFFPAGE..3
R 2
(-4700 4600);
FORCEPROP 2 LAST $XR0 144 
J 0
(-4980 4600);
DISPLAY 0.638298 (-4980 4600);
PAINT MONO (-4980 4600);
FORCEPROP 2 LAST CDS_LIB mstr_standard
J 0
(-4700 4600);
PAINT ORANGE (-4700 4600);
DISPLAY INVISIBLE (-4700 4600);
FORCEPROP 1 LAST OFFPAGE TRUE
J 2
(-5025 4475);
PAINT GREEN (-5025 4475);
DISPLAY INVISIBLE (-5025 4475);
FORCEPROP 1 LAST COMMENT_BODY TRUE
J 2
(-4650 4500);
DISPLAY 1.170213 (-4650 4500);
PAINT GREEN (-4650 4500);
DISPLAY INVISIBLE (-4650 4500);
FORCEPROP 2 LAST PATH I18
J 0
(-4975 4650);
DISPLAY 1.021277 (-4975 4650);
PAINT ORANGE (-4975 4650);
DISPLAY INVISIBLE (-4975 4650);
FORCEADD OFFPAGE..3
R 2
(-4650 3700);
FORCEPROP 2 LAST $XR0 145 
J 0
(-4930 3700);
DISPLAY 0.638298 (-4930 3700);
PAINT MONO (-4930 3700);
FORCEPROP 2 LAST CDS_LIB mstr_standard
J 0
(-4650 3700);
PAINT ORANGE (-4650 3700);
DISPLAY INVISIBLE (-4650 3700);
FORCEPROP 1 LAST OFFPAGE TRUE
J 2
(-4975 3575);
PAINT GREEN (-4975 3575);
DISPLAY INVISIBLE (-4975 3575);
FORCEPROP 1 LAST COMMENT_BODY TRUE
J 2
(-4600 3600);
DISPLAY 1.170213 (-4600 3600);
PAINT GREEN (-4600 3600);
DISPLAY INVISIBLE (-4600 3600);
FORCEPROP 2 LAST PATH I19
J 0
(-4925 3750);
DISPLAY 1.021277 (-4925 3750);
PAINT ORANGE (-4925 3750);
DISPLAY INVISIBLE (-4925 3750);
FORCEADD OFFPAGE..3
(-2175 4600);
FORCEPROP 2 LAST $XR0 108 
J 0
(-1961 4600);
DISPLAY 0.638298 (-1961 4600);
PAINT MONO (-1961 4600);
FORCEPROP 2 LAST $XR1 163 
J 0
(-1841 4600);
DISPLAY 0.638298 (-1841 4600);
PAINT MONO (-1841 4600);
FORCEPROP 2 LAST CDS_LIB mstr_standard
J 0
(-2175 4600);
PAINT ORANGE (-2175 4600);
DISPLAY INVISIBLE (-2175 4600);
FORCEPROP 1 LAST OFFPAGE TRUE
J 0
(-1850 4475);
DISPLAY 0.872340 (-1850 4475);
PAINT GREEN (-1850 4475);
DISPLAY INVISIBLE (-1850 4475);
FORCEPROP 1 LAST COMMENT_BODY TRUE
J 0
(-2225 4500);
DISPLAY 0.872340 (-2225 4500);
PAINT GREEN (-2225 4500);
DISPLAY INVISIBLE (-2225 4500);
FORCEPROP 2 LAST PATH I2
J 0
(-1700 4650);
DISPLAY 1.021277 (-1700 4650);
PAINT ORANGE (-1700 4650);
DISPLAY INVISIBLE (-1700 4650);
FORCEADD OFFPAGE..4
R 2
(-4675 3525);
FORCEPROP 2 LAST $XR0 145 
J 0
(-4957 3525);
DISPLAY 0.638298 (-4957 3525);
PAINT MONO (-4957 3525);
FORCEPROP 2 LAST CDS_LIB mstr_standard
J 0
(-4675 3525);
PAINT ORANGE (-4675 3525);
DISPLAY INVISIBLE (-4675 3525);
FORCEPROP 1 LAST OFFPAGE TRUE
J 2
(-5000 3400);
DISPLAY 0.872340 (-5000 3400);
PAINT GREEN (-5000 3400);
DISPLAY INVISIBLE (-5000 3400);
FORCEPROP 1 LAST COMMENT_BODY TRUE
J 2
(-4650 3425);
DISPLAY 0.872340 (-4650 3425);
PAINT GREEN (-4650 3425);
DISPLAY INVISIBLE (-4650 3425);
FORCEPROP 2 LAST PATH I20
J 0
(-4625 3600);
DISPLAY 1.021277 (-4625 3600);
PAINT ORANGE (-4625 3600);
DISPLAY INVISIBLE (-4625 3600);
FORCEADD RES..1
(-3350 4600);
FORCEPROP 1 LAST LOCATION R1T8
J 0
(-3400 4650);
DISPLAY 0.617021 (-3400 4650);
PAINT AQUA (-3400 4650);
FORCEPROP 1 LAST VALUE 20.0
J 2
(-3050 4600);
DISPLAY 0.617021 (-3050 4600);
PAINT SKYBLUE (-3050 4600);
FORCEPROP 1 LAST TOLERANCE 1%
J 0
(-3225 4600);
DISPLAY 0.617021 (-3225 4600);
PAINT SKYBLUE (-3225 4600);
FORCEPROP 1 LAST MATERIAL CHIP
J 0
(-3550 4600);
DISPLAY 0.617021 (-3550 4600);
PAINT SKYBLUE (-3550 4600);
FORCEPROP 1 LASTPIN (-3250 4600) $PN 2
J 0
(-3288 4612);
DISPLAY 0.617021 (-3288 4612);
PAINT MONO (-3288 4612);
FORCEPROP 1 LASTPIN (-3450 4600) $PN 1
J 0
(-3438 4612);
DISPLAY 0.617021 (-3438 4612);
PAINT MONO (-3438 4612);
FORCEPROP 1 LAST PART_NUMBER G21796-173
J 0
(-3400 4700);
PAINT BLUE (-3400 4700);
DISPLAY INVISIBLE (-3400 4700);
FORCEPROP 1 LAST PACK_TYPE 0402
J 0
(-3100 4450);
PAINT SKYBLUE (-3100 4450);
DISPLAY INVISIBLE (-3100 4450);
FORCEPROP 1 LAST WATTAGE 1/16W
J 2
(-3575 4600);
PAINT SKYBLUE (-3575 4600);
DISPLAY INVISIBLE (-3575 4600);
FORCEPROP 2 LAST BOM_COST SM_CONTROLLER
J 0
(-3400 4750);
DISPLAY 1.021277 (-3400 4750);
PAINT ORANGE (-3400 4750);
DISPLAY INVISIBLE (-3400 4750);
FORCEPROP 2 LAST CDS_LIB mstr_discrete
J 0
(-3350 4600);
PAINT ORANGE (-3350 4600);
DISPLAY INVISIBLE (-3350 4600);
FORCEPROP 2 LAST CDS_SEC 1
J 0
(-3400 4800);
DISPLAY 1.404255 (-3400 4800);
PAINT ORANGE (-3400 4800);
DISPLAY INVISIBLE (-3400 4800);
FORCEPROP 2 LAST $SEC 1
J 0
(-3400 4800);
DISPLAY 0.936170 (-3400 4800);
PAINT MONO (-3400 4800);
DISPLAY INVISIBLE (-3400 4800);
FORCEPROP 2 LAST CDS_LOCATION R1T8
J 0
(-3400 4650);
DISPLAY 0.617021 (-3400 4650);
PAINT AQUA (-3400 4650);
DISPLAY INVISIBLE (-3400 4650);
FORCEPROP 1 LAST PATH I4
J 0
(-3400 4750);
DISPLAY 0.978723 (-3400 4750);
PAINT WHITE (-3400 4750);
DISPLAY INVISIBLE (-3400 4750);
FORCEPROP 2 LAST ROOM SMBUS
J 0
(-3400 4700);
DISPLAY 1.021277 (-3400 4700);
PAINT ORANGE (-3400 4700);
DISPLAY INVISIBLE (-3400 4700);
FORCEADD RES..2
(-4000 4975);
FORCEPROP 1 LAST LOCATION R1T3
J 0
(-3955 5100);
DISPLAY 0.617021 (-3955 5100);
PAINT AQUA (-3955 5100);
FORCEPROP 1 LAST PART_NUMBER G21796-235
J 0
(-3960 4850);
DISPLAY 0.617021 (-3960 4850);
PAINT BLUE (-3960 4850);
FORCEPROP 1 LAST VALUE 665
J 0
(-3955 5050);
DISPLAY 0.617021 (-3955 5050);
PAINT SKYBLUE (-3955 5050);
FORCEPROP 1 LAST TOLERANCE 1.0%
J 0
(-3955 5000);
DISPLAY 0.617021 (-3955 5000);
PAINT SKYBLUE (-3955 5000);
FORCEPROP 1 LAST PACK_TYPE 0402
J 0
(-3960 4800);
DISPLAY 0.617021 (-3960 4800);
PAINT SKYBLUE (-3960 4800);
FORCEPROP 1 LAST MATERIAL CHIP
J 0
(-3960 4900);
DISPLAY 0.617021 (-3960 4900);
PAINT SKYBLUE (-3960 4900);
FORCEPROP 1 LAST WATTAGE 1/16W
J 0
(-3960 4950);
DISPLAY 0.617021 (-3960 4950);
PAINT SKYBLUE (-3960 4950);
FORCEPROP 0 LAST SKU B
J 0
(-3950 5200);
DISPLAY 1.021277 (-3950 5200);
PAINT ORANGE (-3950 5200);
DISPLAY INVISIBLE (-3950 5200);
FORCEPROP 0 LAST BOM_COST SM_CONTROLLER
J 0
(-3950 5300);
DISPLAY 1.021277 (-3950 5300);
PAINT ORANGE (-3950 5300);
DISPLAY INVISIBLE (-3950 5300);
FORCEPROP 2 LAST CDS_LIB mstr_discrete
J 0
(-4000 4975);
PAINT ORANGE (-4000 4975);
DISPLAY INVISIBLE (-4000 4975);
FORCEPROP 2 LAST CDS_SEC 1
J 0
(-3950 5200);
PAINT MONO (-3950 5200);
DISPLAY INVISIBLE (-3950 5200);
FORCEPROP 2 LAST $SEC 1
J 0
(-3950 5200);
PAINT MONO (-3950 5200);
DISPLAY INVISIBLE (-3950 5200);
FORCEPROP 2 LAST CDS_LOCATION R1T3
J 0
(-3955 5100);
DISPLAY 0.617021 (-3955 5100);
PAINT AQUA (-3955 5100);
DISPLAY INVISIBLE (-3955 5100);
FORCEPROP 1 LAST PATH I46
J 0
(-3950 5150);
DISPLAY 0.978723 (-3950 5150);
PAINT WHITE (-3950 5150);
DISPLAY INVISIBLE (-3950 5150);
FORCEPROP 0 LAST ROOM SMBUS
J 0
(-3950 5200);
DISPLAY 1.021277 (-3950 5200);
PAINT ORANGE (-3950 5200);
DISPLAY INVISIBLE (-3950 5200);
FORCEPROP 1 LASTPIN (-4000 4875) $PN 2
J 0
(-3995 4885);
DISPLAY 0.787234 (-3995 4885);
PAINT ORANGE (-3995 4885);
DISPLAY INVISIBLE (-3995 4885);
FORCEPROP 1 LASTPIN (-4000 5075) $PN 1
J 0
(-3995 5037);
DISPLAY 0.787234 (-3995 5037);
PAINT ORANGE (-3995 5037);
DISPLAY INVISIBLE (-3995 5037);
FORCEADD P3V3_STBY..1
(-3650 5275);
FORCEPROP 3 LASTPIN (-3650 5225) SIG_NAME P3V3_STBY\g
J 0
(-3640 5235);
DISPLAY 0.659574 (-3640 5235);
PAINT MONO (-3640 5235);
DISPLAY INVISIBLE (-3640 5235);
FORCEPROP 1 LAST VOLTAGE 3.3V
J 0
(-3695 5232);
DISPLAY 0.340426 (-3695 5232);
PAINT SKYBLUE (-3695 5232);
DISPLAY INVISIBLE (-3695 5232);
FORCEPROP 2 LAST CDS_LIB mstr_symbols
J 0
(-3650 5275);
PAINT MONO (-3650 5275);
DISPLAY INVISIBLE (-3650 5275);
FORCEPROP 1 LAST SIZE 1B
J 0
(-3605 5297);
DISPLAY 0.340426 (-3605 5297);
PAINT GREEN (-3605 5297);
DISPLAY INVISIBLE (-3605 5297);
FORCEPROP 1 LAST BODY_TYPE PLUMBING
J 0
(-3695 5232);
DISPLAY 0.340426 (-3695 5232);
PAINT GREEN (-3695 5232);
DISPLAY INVISIBLE (-3695 5232);
FORCEPROP 1 LAST PATH I47
J 0
(-3605 5277);
DISPLAY 0.340426 (-3605 5277);
PAINT GREEN (-3605 5277);
DISPLAY INVISIBLE (-3605 5277);
FORCEPROP 1 LAST HDL_POWER P3V3_STBY
J 0
(-3950 5150);
DISPLAY 0.872340 (-3950 5150);
PAINT ORANGE (-3950 5150);
DISPLAY INVISIBLE (-3950 5150);
FORCEADD P3V3_STBY..1
(-4000 5275);
FORCEPROP 3 LASTPIN (-4000 5225) SIG_NAME P3V3_STBY\g
J 0
(-3990 5235);
DISPLAY 0.659574 (-3990 5235);
PAINT MONO (-3990 5235);
DISPLAY INVISIBLE (-3990 5235);
FORCEPROP 1 LAST VOLTAGE 3.3V
J 0
(-4045 5232);
DISPLAY 0.340426 (-4045 5232);
PAINT SKYBLUE (-4045 5232);
DISPLAY INVISIBLE (-4045 5232);
FORCEPROP 2 LAST CDS_LIB mstr_symbols
J 0
(-4000 5275);
PAINT MONO (-4000 5275);
DISPLAY INVISIBLE (-4000 5275);
FORCEPROP 1 LAST SIZE 1B
J 0
(-3955 5297);
DISPLAY 0.340426 (-3955 5297);
PAINT GREEN (-3955 5297);
DISPLAY INVISIBLE (-3955 5297);
FORCEPROP 1 LAST BODY_TYPE PLUMBING
J 0
(-4045 5232);
DISPLAY 0.340426 (-4045 5232);
PAINT GREEN (-4045 5232);
DISPLAY INVISIBLE (-4045 5232);
FORCEPROP 1 LAST PATH I48
J 0
(-3955 5277);
DISPLAY 0.340426 (-3955 5277);
PAINT GREEN (-3955 5277);
DISPLAY INVISIBLE (-3955 5277);
FORCEPROP 1 LAST HDL_POWER P3V3_STBY
J 0
(-4300 5150);
DISPLAY 0.872340 (-4300 5150);
PAINT ORANGE (-4300 5150);
DISPLAY INVISIBLE (-4300 5150);
FORCEADD RES..2
(-3650 4975);
FORCEPROP 1 LAST LOCATION R1T2
J 0
(-3605 5100);
DISPLAY 0.617021 (-3605 5100);
PAINT AQUA (-3605 5100);
FORCEPROP 1 LAST PART_NUMBER G21796-235
J 0
(-3610 4850);
DISPLAY 0.617021 (-3610 4850);
PAINT BLUE (-3610 4850);
FORCEPROP 1 LAST VALUE 665
J 0
(-3605 5050);
DISPLAY 0.617021 (-3605 5050);
PAINT SKYBLUE (-3605 5050);
FORCEPROP 1 LAST TOLERANCE 1.0%
J 0
(-3605 5000);
DISPLAY 0.617021 (-3605 5000);
PAINT SKYBLUE (-3605 5000);
FORCEPROP 1 LAST PACK_TYPE 0402
J 0
(-3610 4800);
DISPLAY 0.617021 (-3610 4800);
PAINT SKYBLUE (-3610 4800);
FORCEPROP 1 LAST MATERIAL CHIP
J 0
(-3610 4900);
DISPLAY 0.617021 (-3610 4900);
PAINT SKYBLUE (-3610 4900);
FORCEPROP 1 LAST WATTAGE 1/16W
J 0
(-3610 4950);
DISPLAY 0.617021 (-3610 4950);
PAINT SKYBLUE (-3610 4950);
FORCEPROP 0 LAST SKU B
J 0
(-3600 5200);
DISPLAY 1.021277 (-3600 5200);
PAINT ORANGE (-3600 5200);
DISPLAY INVISIBLE (-3600 5200);
FORCEPROP 0 LAST BOM_COST SM_CONTROLLER
J 0
(-3600 5300);
DISPLAY 1.021277 (-3600 5300);
PAINT ORANGE (-3600 5300);
DISPLAY INVISIBLE (-3600 5300);
FORCEPROP 2 LAST CDS_LIB mstr_discrete
J 0
(-3650 4975);
PAINT ORANGE (-3650 4975);
DISPLAY INVISIBLE (-3650 4975);
FORCEPROP 2 LAST CDS_SEC 1
J 0
(-3600 5200);
PAINT MONO (-3600 5200);
DISPLAY INVISIBLE (-3600 5200);
FORCEPROP 2 LAST $SEC 1
J 0
(-3600 5200);
PAINT MONO (-3600 5200);
DISPLAY INVISIBLE (-3600 5200);
FORCEPROP 2 LAST CDS_LOCATION R1T2
J 0
(-3605 5100);
DISPLAY 0.617021 (-3605 5100);
PAINT AQUA (-3605 5100);
DISPLAY INVISIBLE (-3605 5100);
FORCEPROP 1 LAST PATH I49
J 0
(-3600 5150);
DISPLAY 0.978723 (-3600 5150);
PAINT WHITE (-3600 5150);
DISPLAY INVISIBLE (-3600 5150);
FORCEPROP 0 LAST ROOM SMBUS
J 0
(-3600 5200);
DISPLAY 1.021277 (-3600 5200);
PAINT ORANGE (-3600 5200);
DISPLAY INVISIBLE (-3600 5200);
FORCEPROP 1 LASTPIN (-3650 4875) $PN 2
J 0
(-3645 4885);
DISPLAY 0.787234 (-3645 4885);
PAINT ORANGE (-3645 4885);
DISPLAY INVISIBLE (-3645 4885);
FORCEPROP 1 LASTPIN (-3650 5075) $PN 1
J 0
(-3645 5037);
DISPLAY 0.787234 (-3645 5037);
PAINT ORANGE (-3645 5037);
DISPLAY INVISIBLE (-3645 5037);
FORCEADD RES..1
(-3350 4425);
FORCEPROP 1 LAST LOCATION R1T7
J 0
(-3400 4475);
DISPLAY 0.617021 (-3400 4475);
PAINT AQUA (-3400 4475);
FORCEPROP 1 LAST VALUE 20.0
J 2
(-3050 4425);
DISPLAY 0.617021 (-3050 4425);
PAINT SKYBLUE (-3050 4425);
FORCEPROP 1 LAST TOLERANCE 1%
J 0
(-3225 4425);
DISPLAY 0.617021 (-3225 4425);
PAINT SKYBLUE (-3225 4425);
FORCEPROP 1 LAST MATERIAL CHIP
J 0
(-3550 4425);
DISPLAY 0.617021 (-3550 4425);
PAINT SKYBLUE (-3550 4425);
FORCEPROP 1 LASTPIN (-3250 4425) $PN 2
J 0
(-3288 4437);
DISPLAY 0.617021 (-3288 4437);
PAINT MONO (-3288 4437);
FORCEPROP 1 LASTPIN (-3450 4425) $PN 1
J 0
(-3438 4437);
DISPLAY 0.617021 (-3438 4437);
PAINT MONO (-3438 4437);
FORCEPROP 1 LAST PART_NUMBER G21796-173
J 0
(-3400 4525);
PAINT BLUE (-3400 4525);
DISPLAY INVISIBLE (-3400 4525);
FORCEPROP 1 LAST PACK_TYPE 0402
J 0
(-3100 4275);
PAINT SKYBLUE (-3100 4275);
DISPLAY INVISIBLE (-3100 4275);
FORCEPROP 1 LAST WATTAGE 1/16W
J 2
(-3575 4425);
PAINT SKYBLUE (-3575 4425);
DISPLAY INVISIBLE (-3575 4425);
FORCEPROP 2 LAST BOM_COST SM_CONTROLLER
J 0
(-3400 4575);
DISPLAY 1.021277 (-3400 4575);
PAINT ORANGE (-3400 4575);
DISPLAY INVISIBLE (-3400 4575);
FORCEPROP 2 LAST CDS_LIB mstr_discrete
J 0
(-3350 4425);
PAINT ORANGE (-3350 4425);
DISPLAY INVISIBLE (-3350 4425);
FORCEPROP 2 LAST CDS_SEC 1
J 0
(-3400 4625);
DISPLAY 1.404255 (-3400 4625);
PAINT ORANGE (-3400 4625);
DISPLAY INVISIBLE (-3400 4625);
FORCEPROP 2 LAST $SEC 1
J 0
(-3400 4625);
DISPLAY 0.936170 (-3400 4625);
PAINT MONO (-3400 4625);
DISPLAY INVISIBLE (-3400 4625);
FORCEPROP 2 LAST CDS_LOCATION R1T7
J 0
(-3400 4475);
DISPLAY 0.617021 (-3400 4475);
PAINT AQUA (-3400 4475);
DISPLAY INVISIBLE (-3400 4475);
FORCEPROP 1 LAST PATH I50
J 0
(-3400 4575);
DISPLAY 0.978723 (-3400 4575);
PAINT WHITE (-3400 4575);
DISPLAY INVISIBLE (-3400 4575);
FORCEPROP 2 LAST ROOM SMBUS
J 0
(-3400 4525);
DISPLAY 1.021277 (-3400 4525);
PAINT ORANGE (-3400 4525);
DISPLAY INVISIBLE (-3400 4525);
FORCEADD RES..1
(-3350 3700);
FORCEPROP 1 LAST LOCATION R9F23
J 0
(-3400 3750);
DISPLAY 0.617021 (-3400 3750);
PAINT AQUA (-3400 3750);
FORCEPROP 1 LAST VALUE 20.0
J 2
(-3050 3700);
DISPLAY 0.617021 (-3050 3700);
PAINT SKYBLUE (-3050 3700);
FORCEPROP 1 LAST TOLERANCE 1%
J 0
(-3225 3700);
DISPLAY 0.617021 (-3225 3700);
PAINT SKYBLUE (-3225 3700);
FORCEPROP 1 LAST MATERIAL CHIP
J 0
(-3550 3700);
DISPLAY 0.617021 (-3550 3700);
PAINT SKYBLUE (-3550 3700);
FORCEPROP 1 LASTPIN (-3250 3700) $PN 2
J 0
(-3288 3712);
DISPLAY 0.617021 (-3288 3712);
PAINT MONO (-3288 3712);
FORCEPROP 1 LASTPIN (-3450 3700) $PN 1
J 0
(-3438 3712);
DISPLAY 0.617021 (-3438 3712);
PAINT MONO (-3438 3712);
FORCEPROP 1 LAST PART_NUMBER G21796-173
J 0
(-3400 3800);
PAINT BLUE (-3400 3800);
DISPLAY INVISIBLE (-3400 3800);
FORCEPROP 1 LAST PACK_TYPE 0402
J 0
(-3100 3550);
PAINT SKYBLUE (-3100 3550);
DISPLAY INVISIBLE (-3100 3550);
FORCEPROP 1 LAST WATTAGE 1/16W
J 2
(-3575 3700);
PAINT SKYBLUE (-3575 3700);
DISPLAY INVISIBLE (-3575 3700);
FORCEPROP 2 LAST BOM_COST SM_CONTROLLER
J 0
(-3400 3850);
DISPLAY 1.021277 (-3400 3850);
PAINT ORANGE (-3400 3850);
DISPLAY INVISIBLE (-3400 3850);
FORCEPROP 2 LAST CDS_LIB mstr_discrete
J 0
(-3350 3700);
PAINT ORANGE (-3350 3700);
DISPLAY INVISIBLE (-3350 3700);
FORCEPROP 2 LAST CDS_SEC 1
J 0
(-3400 3900);
DISPLAY 1.404255 (-3400 3900);
PAINT ORANGE (-3400 3900);
DISPLAY INVISIBLE (-3400 3900);
FORCEPROP 2 LAST $SEC 1
J 0
(-3400 3900);
DISPLAY 0.936170 (-3400 3900);
PAINT MONO (-3400 3900);
DISPLAY INVISIBLE (-3400 3900);
FORCEPROP 2 LAST CDS_LOCATION R9F23
J 0
(-3400 3750);
DISPLAY 0.617021 (-3400 3750);
PAINT AQUA (-3400 3750);
DISPLAY INVISIBLE (-3400 3750);
FORCEPROP 1 LAST PATH I51
J 0
(-3400 3850);
DISPLAY 0.978723 (-3400 3850);
PAINT WHITE (-3400 3850);
DISPLAY INVISIBLE (-3400 3850);
FORCEPROP 2 LAST ROOM SMBUS
J 0
(-3400 3800);
DISPLAY 1.021277 (-3400 3800);
PAINT ORANGE (-3400 3800);
DISPLAY INVISIBLE (-3400 3800);
FORCEADD RES..1
(-3350 3525);
FORCEPROP 1 LAST LOCATION R9F22
J 0
(-3400 3575);
DISPLAY 0.617021 (-3400 3575);
PAINT AQUA (-3400 3575);
FORCEPROP 1 LAST VALUE 20.0
J 2
(-3050 3525);
DISPLAY 0.617021 (-3050 3525);
PAINT SKYBLUE (-3050 3525);
FORCEPROP 1 LAST TOLERANCE 1%
J 0
(-3225 3525);
DISPLAY 0.617021 (-3225 3525);
PAINT SKYBLUE (-3225 3525);
FORCEPROP 1 LAST MATERIAL CHIP
J 0
(-3550 3525);
DISPLAY 0.617021 (-3550 3525);
PAINT SKYBLUE (-3550 3525);
FORCEPROP 1 LASTPIN (-3250 3525) $PN 2
J 0
(-3288 3537);
DISPLAY 0.617021 (-3288 3537);
PAINT MONO (-3288 3537);
FORCEPROP 1 LASTPIN (-3450 3525) $PN 1
J 0
(-3438 3537);
DISPLAY 0.617021 (-3438 3537);
PAINT MONO (-3438 3537);
FORCEPROP 1 LAST PART_NUMBER G21796-173
J 0
(-3400 3625);
PAINT BLUE (-3400 3625);
DISPLAY INVISIBLE (-3400 3625);
FORCEPROP 1 LAST PACK_TYPE 0402
J 0
(-3100 3375);
PAINT SKYBLUE (-3100 3375);
DISPLAY INVISIBLE (-3100 3375);
FORCEPROP 1 LAST WATTAGE 1/16W
J 2
(-3575 3525);
PAINT SKYBLUE (-3575 3525);
DISPLAY INVISIBLE (-3575 3525);
FORCEPROP 2 LAST BOM_COST SM_CONTROLLER
J 0
(-3400 3675);
DISPLAY 1.021277 (-3400 3675);
PAINT ORANGE (-3400 3675);
DISPLAY INVISIBLE (-3400 3675);
FORCEPROP 2 LAST CDS_LIB mstr_discrete
J 0
(-3350 3525);
PAINT ORANGE (-3350 3525);
DISPLAY INVISIBLE (-3350 3525);
FORCEPROP 2 LAST CDS_SEC 1
J 0
(-3400 3725);
DISPLAY 1.404255 (-3400 3725);
PAINT ORANGE (-3400 3725);
DISPLAY INVISIBLE (-3400 3725);
FORCEPROP 2 LAST $SEC 1
J 0
(-3400 3725);
DISPLAY 0.936170 (-3400 3725);
PAINT MONO (-3400 3725);
DISPLAY INVISIBLE (-3400 3725);
FORCEPROP 2 LAST CDS_LOCATION R9F22
J 0
(-3400 3575);
DISPLAY 0.617021 (-3400 3575);
PAINT AQUA (-3400 3575);
DISPLAY INVISIBLE (-3400 3575);
FORCEPROP 1 LAST PATH I52
J 0
(-3400 3675);
DISPLAY 0.978723 (-3400 3675);
PAINT WHITE (-3400 3675);
DISPLAY INVISIBLE (-3400 3675);
FORCEPROP 2 LAST ROOM SMBUS
J 0
(-3400 3625);
DISPLAY 1.021277 (-3400 3625);
PAINT ORANGE (-3400 3625);
DISPLAY INVISIBLE (-3400 3625);
FORCEADD OFFPAGE..2
(-2175 3525);
FORCEPROP 2 LAST $XR0 138 
J 0
(-1986 3525);
DISPLAY 0.638298 (-1986 3525);
PAINT MONO (-1986 3525);
FORCEPROP 2 LAST $XR1 156 
J 0
(-1866 3525);
DISPLAY 0.638298 (-1866 3525);
PAINT MONO (-1866 3525);
FORCEPROP 2 LAST $XR2 182 
J 0
(-1746 3525);
DISPLAY 0.638298 (-1746 3525);
PAINT MONO (-1746 3525);
FORCEPROP 2 LAST $XR4 ?
J 0
(-1746 3525);
DISPLAY 0.638298 (-1746 3525);
PAINT MONO (-1746 3525);
FORCEPROP 2 LAST $XR3 ?
J 0
(-1746 3525);
DISPLAY 0.638298 (-1746 3525);
PAINT MONO (-1746 3525);
FORCEPROP 2 LAST CDS_LIB mstr_standard
J 0
(-2175 3525);
PAINT ORANGE (-2175 3525);
DISPLAY INVISIBLE (-2175 3525);
FORCEPROP 1 LAST OFFPAGE TRUE
J 0
(-1850 3400);
DISPLAY 0.872340 (-1850 3400);
PAINT GREEN (-1850 3400);
DISPLAY INVISIBLE (-1850 3400);
FORCEPROP 1 LAST COMMENT_BODY TRUE
J 0
(-2220 3430);
DISPLAY 0.872340 (-2220 3430);
PAINT GREEN (-2220 3430);
DISPLAY INVISIBLE (-2220 3430);
FORCEPROP 2 LAST PATH I9
J 0
(-2000 3600);
DISPLAY 1.021277 (-2000 3600);
PAINT ORANGE (-2000 3600);
DISPLAY INVISIBLE (-2000 3600);
FORCEADD CAD_NOTE..1
(-3425 3350);
FORCEPROP 0 LAST L1 PLACE RESISTORS CLOSE TO BMC
J 0
(-4100 3200);
DISPLAY 1.021277 (-4100 3200);
PAINT ORANGE (-4100 3200);
FORCEPROP 2 LAST CDS_LIB mstr_symbols
J 0
(-3425 3350);
PAINT ORANGE (-3425 3350);
DISPLAY INVISIBLE (-3425 3350);
FORCEPROP 1 LAST COMMENT_BODY TRUE
J 0
(-3400 3450);
DISPLAY 0.978723 (-3400 3450);
PAINT ORANGE (-3400 3450);
DISPLAY INVISIBLE (-3400 3450);
FORCEADD DESIGN_NOTE..1
(-1900 1175);
FORCEPROP 0 LAST L1 REMOVE 0 OHM RESISTOR  AND STUFF PULL-UP RES ON VR SMBUS IN MASS PRODUCTION
J 0
(-2100 1050);
DISPLAY 0.617021 (-2100 1050);
PAINT WHITE (-2100 1050);
FORCEPROP 2 LAST CDS_LIB mstr_symbols
J 0
(-1900 1175);
PAINT WHITE (-1900 1175);
DISPLAY INVISIBLE (-1900 1175);
FORCEPROP 1 LAST COMMENT_BODY TRUE
J 0
(-1875 1275);
DISPLAY 1.319149 (-1875 1275);
PAINT WHITE (-1875 1275);
DISPLAY INVISIBLE (-1875 1275);
FORCEADD INTEL_CORP_BPAGE..1
(2600 525);
FORCEPROP 1 LAST CDS_CON_LAST_MODIFIED Tue Dec 01 11:52:10 2015
J 0
(1175 850);
DISPLAY 1.361702 (1175 850);
PAINT GREEN (1175 850);
DISPLAY INVISIBLE (1175 850);
FORCEPROP 1 LAST CUSTOM_TXT_CDS <CURRENT_DESIGN_SHEET> OF <TOTAL_DESIGN_SHEETS>
J 0
(2100 550);
PAINT GREEN (2100 550);
FORCEPROP 1 LAST CUSTOM_TXT_CDS <CON_LAST_MODIFIED>
J 0
(675 875);
PAINT GREEN (675 875);
FORCEPROP 2 LAST CUSTOM_TXT_CDS <XR_PAGE_TITLE>
J 0
(-5290 5775);
DISPLAY 0.638298 (-5290 5775);
PAINT PINK (-5290 5775);
DISPLAY INVISIBLE (-5290 5775);
FORCEPROP 1 LAST SCH_ADDRESS3 Santa Clara, CA 95052-8119
J 0
(-1375 550);
DISPLAY 0.617021 (-1375 550);
PAINT GREEN (-1375 550);
FORCEPROP 1 LAST SCH_ADDRESS2 P.O. BOX 58119
J 0
(-1375 600);
DISPLAY 0.617021 (-1375 600);
PAINT GREEN (-1375 600);
FORCEPROP 1 LAST SCH_ADDRESS1 2200 Mission College Blvd.
J 0
(-1375 650);
DISPLAY 0.617021 (-1375 650);
PAINT GREEN (-1375 650);
FORCEPROP 1 LAST SCH_TITLE SMBUS PULLUPS (2 OF 2)
J 0
(-5350 575);
DISPLAY 1.212766 (-5350 575);
PAINT ORANGE (-5350 575);
FORCEPROP 1 LAST SCH_NUMBER H4694802
J 0
(1300 675);
DISPLAY 1.212766 (1300 675);
PAINT YELLOW (1300 675);
FORCEPROP 1 LAST SCH_DEPT BESD
J 1
(-1850 625);
DISPLAY 1.212766 (-1850 625);
PAINT YELLOW (-1850 625);
FORCEPROP 1 LAST SCH_REV 2.420
J 0
(2350 675);
DISPLAY 0.978723 (2350 675);
PAINT YELLOW (2350 675);
FORCEPROP 2 LAST PAGE_BORDER TRUE
J 0
(-5290 5775);
DISPLAY 0.851064 (-5290 5775);
PAINT PINK (-5290 5775);
DISPLAY INVISIBLE (-5290 5775);
FORCEPROP 2 LAST CDS_LIB mstr_symbols
J 0
(2600 525);
PAINT MONO (2600 525);
DISPLAY INVISIBLE (2600 525);
FORCEPROP 1 LAST COMMENT_BODY TRUE
J 0
(2612 537);
DISPLAY 0.617021 (2612 537);
PAINT GREEN (2612 537);
DISPLAY INVISIBLE (2612 537);
FORCEPROP 2 LAST CDS_XR_PAGE_TITLE CR-160 : @BASEBOARD_FAB2_LIB.BASEBOARD_FAB2(SCH_1):PAGE160
J 0
(-5290 5775);
DISPLAY 0.638298 (-5290 5775);
PAINT PINK (-5290 5775);
DISPLAY INVISIBLE (-5290 5775);
WIRE 16 -1 (-3650 5225)(-3650 5075);
WIRE 16 -1 (-4000 5225)(-4000 5075);
WIRE 16 2175 (-3025 5400)(-3025 3150);
WIRE 16 2175 (-4225 5400)(-3025 5400);
WIRE 16 2175 (-3025 3150)(-4225 3150);
WIRE 16 2175 (-4225 3150)(-4225 5400);
WIRE 16 -1 (-4600 3700)(-3450 3700);
FORCEPROP 2 LAST SIG_NAME SMB_LAN_STBY_LVC3_SDA_R
J 0
(-4610 3710);
DISPLAY 0.617021 (-4610 3710);
PAINT ORANGE (-4610 3710);
WIRE 16 -1 (-4625 3525)(-3450 3525);
FORCEPROP 2 LAST SIG_NAME SMB_LAN_STBY_LVC3_SCL_R
J 0
(-4610 3535);
DISPLAY 0.617021 (-4610 3535);
PAINT ORANGE (-4610 3535);
WIRE 16 -1 (-3250 3700)(-2225 3700);
FORCEPROP 0 LAST SIG_NAME SMB_LAN_STBY_LVC3_SDA
J 2
(-2200 3710);
DISPLAY 0.617021 (-2200 3710);
PAINT ORANGE (-2200 3710);
WIRE 16 -1 (-3250 3525)(-2225 3525);
FORCEPROP 0 LAST SIG_NAME SMB_LAN_STBY_LVC3_SCL
J 2
(-2200 3535);
DISPLAY 0.617021 (-2200 3535);
PAINT ORANGE (-2200 3535);
WIRE 16 -1 (-3650 4875)(-3650 4425);
WIRE 16 -1 (-3650 4425)(-3450 4425);
WIRE 16 -1 (-4650 4425)(-3650 4425);
FORCEPROP 2 LAST SIG_NAME SMB_SLOTX24_STBY_LVC3_SCL_R
J 0
(-4635 4435);
DISPLAY 0.617021 (-4635 4435);
PAINT ORANGE (-4635 4435);
WIRE 16 -1 (-4000 4875)(-4000 4600);
WIRE 16 -1 (-4000 4600)(-3450 4600);
WIRE 16 -1 (-4650 4600)(-4000 4600);
FORCEPROP 2 LAST SIG_NAME SMB_SLOTX24_STBY_LVC3_SDA_R
J 0
(-4660 4610);
DISPLAY 0.617021 (-4660 4610);
PAINT ORANGE (-4660 4610);
WIRE 16 -1 (-3250 4425)(-2225 4425);
FORCEPROP 0 LAST SIG_NAME SMB_SLOTX24_BMC_STBY_LVC3_SCL
J 2
(-2200 4435);
DISPLAY 0.617021 (-2200 4435);
PAINT ORANGE (-2200 4435);
WIRE 16 -1 (-3250 4600)(-2225 4600);
FORCEPROP 0 LAST SIG_NAME SMB_SLOTX24_BMC_STBY_LVC3_SDA
J 2
(-2200 4610);
DISPLAY 0.617021 (-2200 4610);
PAINT ORANGE (-2200 4610);
DOT 1 (-3650 4425);
DOT 1 (-4000 4600);
QUIT
